# T6G (Grand Teton) — schematic netlist excerpt (pin names and nets, part order shuffled) for the footprints in the layout excerpt that follows; sources: Cadence DE-HDL packaged netlist, KiCad conversion of 04192023_DAF0TMB3IC0_F0TG_MB_C_brd_V02_OCP.brd

J99  SCONN288_DDR506112002KQ  IO  pkg DDR288S_1-1VXC  page 108
  VIN_BULK0  = P12V_MEM_CPU1
  RFU0  = NC
  VIN_MGMT  = P3V3_AUX
  HSCL  = I3C_SPD_DDRK_CPU1_SCL
  HSDA  = I3C_SPD_DDRK_CPU1_SDA
  VSS0  = GND
  DQ0_A  = M_K_CPU1_SA_DQ<0>
  VSS1  = GND
  DQ1_A  = M_K_CPU1_SA_DQ<1>
  VSS2  = GND
  DQS0_A_T  = M_K_CPU1_SA_DQS_DP<0>
  DQS0_A_C  = M_K_CPU1_SA_DQS_DN<0>
  VSS3  = GND
  DQ4_A  = M_K_CPU1_SA_DQ<4>
  VSS4  = GND
  DQ5_A  = M_K_CPU1_SA_DQ<5>
  VSS5  = GND
  DQ8_A  = M_K_CPU1_SA_DQ<8>
  VSS6  = GND
  DQ9_A  = M_K_CPU1_SA_DQ<9>
  VSS7  = GND
  DQS1_A_T  = M_K_CPU1_SA_DQS_DP<1>
  DQS1_A_C  = M_K_CPU1_SA_DQS_DN<1>
  VSS8  = GND
  DQ12_A  = M_K_CPU1_SA_DQ<12>
  VSS9  = GND
  DQ13_A  = M_K_CPU1_SA_DQ<13>
  VSS10  = GND
  DQ16_A  = M_K_CPU1_SA_DQ<16>
  VSS11  = GND
  DQ17_A  = M_K_CPU1_SA_DQ<17>
  VSS12  = GND
  DQS2_A_T  = M_K_CPU1_SA_DQS_DP<2>
  DQS2_A_C  = M_K_CPU1_SA_DQS_DN<2>
  VSS13  = GND
  DQ20_A  = M_K_CPU1_SA_DQ<20>
  VSS14  = GND
  DQ21_A  = M_K_CPU1_SA_DQ<21>
  VSS15  = GND
  DQ24_A  = M_K_CPU1_SA_DQ<24>
  VSS16  = GND
  DQ25_A  = M_K_CPU1_SA_DQ<25>
  VSS17  = GND
  DQS3_A_T  = M_K_CPU1_SA_DQS_DP<3>
  DQS3_A_C  = M_K_CPU1_SA_DQS_DN<3>
  VSS18  = GND
  DQ28_A  = M_K_CPU1_SA_DQ<28>
  VSS19  = GND
  DQ29_A  = M_K_CPU1_SA_DQ<29>
  VSS20  = GND
  CB0_A  = M_K_CPU1_SA_CB<0>
  VSS21  = GND
  CB1_A  = M_K_CPU1_SA_CB<1>
  VSS22  = GND
  DQS4_A_T  = M_K_CPU1_SA_DQS_DP<4>
  DQS4_A_C  = M_K_CPU1_SA_DQS_DN<4>
  VSS23  = GND
  CB4_A  = M_K_CPU1_SA_CB<4>
  VSS24  = GND
  CB5_A  = M_K_CPU1_SA_CB<5>
  VSS25  = GND
  ALERT_N  = M_K_CPU1_ALERT_N
  VSS26  = GND
  CS0_A_N  = M_K_CPU1_SA_CS_N<0>
  VSS27  = GND
  CA0_A  = M_K_CPU1_SA_CA<0>
  VSS28  = GND
  CA2_A  = M_K_CPU1_SA_CA<2>
  VSS29  = GND
  CA4_A  = M_K_CPU1_SA_CA<4>
  VSS30  = GND
  CA6_A  = M_K_CPU1_SA_CA<6>
  VSS31  = GND
  PAR_A  = M_K_CPU1_SA_PAR
  VSS32  = GND
  CA0_B  = M_K_CPU1_SB_CA<0>
  VSS33  = GND
  CA2_B  = M_K_CPU1_SB_CA<2>
  VSS34  = GND
  CA4_B  = M_K_CPU1_SB_CA<4>
  VSS35  = GND
  CA6_B  = M_K_CPU1_SB_CA<6>
  VSS36  = GND
  CS0_B_N  = M_K_CPU1_SB_CS_N<0>
  VSS37  = GND
  \lbd||rsp_a_n\  = M_K_CPU1_SA_RSP<0>
  \lbs||rsp_b_n\  = M_K_CPU1_SB_RSP<0>
  VSS38  = GND
  CB4_B  = M_K_CPU1_SB_CB<4>
  VSS39  = GND
  CB5_B  = M_K_CPU1_SB_CB<5>
  VSS40  = GND
  \dqs9_b_t||tdqs9_b_t||dbi4_b_n\  = M_K_CPU1_SB_DQS_DP<9>
  \dqs9_b_c||tdqs9_b_c\  = M_K_CPU1_SB_DQS_DN<9>
  VSS41  = GND
  CB0_B  = M_K_CPU1_SB_CB<0>
  VSS42  = GND
  CB1_B  = M_K_CPU1_SB_CB<1>
  VSS43  = GND
  DQ0_B  = M_K_CPU1_SB_DQ<0>
  VSS44  = GND
  DQ1_B  = M_K_CPU1_SB_DQ<1>
  VSS45  = GND
  DQS0_B_T  = M_K_CPU1_SB_DQS_DP<0>
  DQS0_B_C  = M_K_CPU1_SB_DQS_DN<0>
  VSS46  = GND
  DQ4_B  = M_K_CPU1_SB_DQ<4>
  VSS47  = GND
  DQ5_B  = M_K_CPU1_SB_DQ<5>
  VSS48  = GND
  DQ8_B  = M_K_CPU1_SB_DQ<8>
  VSS49  = GND
  DQ9_B  = M_K_CPU1_SB_DQ<9>
  VSS50  = GND
  DQS1_B_T  = M_K_CPU1_SB_DQS_DP<1>
  DQS1_B_C  = M_K_CPU1_SB_DQS_DN<1>
  VSS51  = GND
  DQ12_B  = M_K_CPU1_SB_DQ<12>
  VSS52  = GND
  DQ13_B  = M_K_CPU1_SB_DQ<13>
  VSS53  = GND
  DQ16_B  = M_K_CPU1_SB_DQ<16>
  VSS54  = GND
  DQ17_B  = M_K_CPU1_SB_DQ<17>
  VSS55  = GND
  DQS2_B_T  = M_K_CPU1_SB_DQS_DP<2>
  DQS2_B_C  = M_K_CPU1_SB_DQS_DN<2>
  VSS56  = GND
  DQ20_B  = M_K_CPU1_SB_DQ<20>
  VSS57  = GND
  DQ21_B  = M_K_CPU1_SB_DQ<21>
  VSS58  = GND
  DQ24_B  = M_K_CPU1_SB_DQ<24>
  VSS59  = GND
  DQ25_B  = M_K_CPU1_SB_DQ<25>
  VSS60  = GND
  DQS3_B_T  = M_K_CPU1_SB_DQS_DP<3>
  DQS3_B_C  = M_K_CPU1_SB_DQS_DN<3>
  VSS61  = GND
  DQ28_B  = M_K_CPU1_SB_DQ<28>
  VSS62  = GND
  DQ29_B  = M_K_CPU1_SB_DQ<29>
  VSS63  = GND
  RFU1  = NC
  VIN_BULK1  = P12V_MEM_CPU1
  VIN_BULK2  = P12V_MEM_CPU1
  \pwr_good||fail_n\  = PWRGD_CHK_CPU1_DIMM
  HAS  = PD_CHK_CPU1_DIMM_SAA
  RFU2  = NC
  RFU3  = NC
  VSS64  = GND
  DQ2_A  = M_K_CPU1_SA_DQ<2>
  VSS65  = GND
  DQ3_A  = M_K_CPU1_SA_DQ<3>
  VSS66  = GND
  \dqs5_a_c||tdqs5_a_c||dqs5_a_t||tdqs5_a_t\  = M_K_CPU1_SA_DQS_DN<5>
  \dqs5_a_t||tdqs5_a_t\  = M_K_CPU1_SA_DQS_DP<5>
  VSS67  = GND
  DQ6_A  = M_K_CPU1_SA_DQ<6>
  VSS68  = GND
  DQ7_A  = M_K_CPU1_SA_DQ<7>
  VSS69  = GND
  DQ10_A  = M_K_CPU1_SA_DQ<10>
  VSS70  = GND
  DQ11_A  = M_K_CPU1_SA_DQ<11>
  VSS71  = GND
  \dqs6_a_c||tdqs6_a_c||dqs6_a_t||tdqs6_a_t\  = M_K_CPU1_SA_DQS_DN<6>
  \dqs6_a_t||tdqs6_a_t\  = M_K_CPU1_SA_DQS_DP<6>
  VSS72  = GND
  DQ14_A  = M_K_CPU1_SA_DQ<14>
  VSS73  = GND
  DQ15_A  = M_K_CPU1_SA_DQ<15>
  VSS74  = GND
  DQ18_A  = M_K_CPU1_SA_DQ<18>
  VSS75  = GND
  DQ19_A  = M_K_CPU1_SA_DQ<19>
  VSS76  = GND
  \dqs7_a_c||tdqs7_a_c\  = M_K_CPU1_SA_DQS_DN<7>
  \dqs7_a_t||tdqs7_a_t\  = M_K_CPU1_SA_DQS_DP<7>
  VSS77  = GND
  DQ22_A  = M_K_CPU1_SA_DQ<22>
  VSS78  = GND
  DQ23_A  = M_K_CPU1_SA_DQ<23>
  VSS79  = GND
  DQ26_A  = M_K_CPU1_SA_DQ<26>
  VSS80  = GND
  DQ27_A  = M_K_CPU1_SA_DQ<27>
  VSS81  = GND
  \dqs8_a_c||tdqs8_a_c\  = M_K_CPU1_SA_DQS_DN<8>
  \dqs8_a_t||tdqs8_a_t\  = M_K_CPU1_SA_DQS_DP<8>
  VSS82  = GND
  DQ30_A  = M_K_CPU1_SA_DQ<30>
  VSS83  = GND
  DQ31_A  = M_K_CPU1_SA_DQ<31>
  VSS84  = GND
  CB2_A  = M_K_CPU1_SA_CB<2>
  VSS85  = GND
  CB3_A  = M_K_CPU1_SA_CB<3>
  VSS86  = GND
  \dqs9_a_c||tdqs9_a_c\  = M_K_CPU1_SA_DQS_DN<9>
  \dqs9_a_t||tdqs9_a_t\  = M_K_CPU1_SA_DQS_DP<9>
  VSS87  = GND
  CB6_A  = M_K_CPU1_SA_CB<6>
  VSS88  = GND
  CB7_A  = M_K_CPU1_SA_CB<7>
  VSS89  = GND
  RESET_N  = M_K_CPU1_RESET_N
  VSS90  = GND
  CS1_A_N  = M_K_CPU1_SA_CS_N<1>
  VSS91  = GND
  CA1_A  = M_K_CPU1_SA_CA<1>
  VSS92  = GND
  CA3_A  = M_K_CPU1_SA_CA<3>
  VSS93  = GND
  CA5_A  = M_K_CPU1_SA_CA<5>
  VSS94  = GND
  CK_T  = M_K_CPU1_CLK_DP<0>
  CK_C  = M_K_CPU1_CLK_DN<0>
  VSS95  = GND
  RFU4  = NC
  CA1_B  = M_K_CPU1_SB_CA<1>
  VSS96  = GND
  CA3_B  = M_K_CPU1_SB_CA<3>
  VSS97  = GND
  CA5_B  = M_K_CPU1_SB_CA<5>
  VSS98  = GND
  PAR_B  = M_K_CPU1_SB_PAR
  VSS99  = GND
  CS1_B_N  = M_K_CPU1_SB_CS_N<1>
  VSS100  = GND
  RFU5  = NC
  RFU6  = NC
  VSS101  = GND
  CB6_B  = M_K_CPU1_SB_CB<6>
  VSS102  = GND
  CB7_B  = M_K_CPU1_SB_CB<7>
  VSS103  = GND
  DQS4_B_C  = M_K_CPU1_SB_DQS_DN<4>
  DQS4_B_T  = M_K_CPU1_SB_DQS_DP<4>
  VSS104  = GND
  CB2_B  = M_K_CPU1_SB_CB<2>
  VSS105  = GND
  CB3_B  = M_K_CPU1_SB_CB<3>
  VSS106  = GND
  DQ2_B  = M_K_CPU1_SB_DQ<2>
  VSS107  = GND
  DQ3_B  = M_K_CPU1_SB_DQ<3>
  VSS108  = GND
  \dqs5_b_c||tdqs5_b_c\  = M_K_CPU1_SB_DQS_DN<5>
  \dqs5_b_t||tdqs5_b_t\  = M_K_CPU1_SB_DQS_DP<5>
  VSS109  = GND
  DQ6_B  = M_K_CPU1_SB_DQ<6>
  VSS110  = GND
  DQ7_B  = M_K_CPU1_SB_DQ<7>
  VSS111  = GND
  DQ10_B  = M_K_CPU1_SB_DQ<10>
  VSS112  = GND
  DQ11_B  = M_K_CPU1_SB_DQ<11>
  VSS113  = GND
  \dqs6_b_c||tdqs6_b_c\  = M_K_CPU1_SB_DQS_DN<6>
  \dqs6_b_t||tdqs6_b_t\  = M_K_CPU1_SB_DQS_DP<6>
  VSS114  = GND
  DQ14_B  = M_K_CPU1_SB_DQ<14>
  VSS115  = GND
  DQ15_B  = M_K_CPU1_SB_DQ<15>
  VSS116  = GND
  DQ18_B  = M_K_CPU1_SB_DQ<18>
  VSS117  = GND
  DQ19_B  = M_K_CPU1_SB_DQ<19>
  VSS118  = GND
  \dqs7_b_c||tdqs7_b_c\  = M_K_CPU1_SB_DQS_DN<7>
  \dqs7_b_t||tdqs7_b_t\  = M_K_CPU1_SB_DQS_DP<7>
  VSS119  = GND
  DQ22_B  = M_K_CPU1_SB_DQ<22>
  VSS120  = GND
  DQ23_B  = M_K_CPU1_SB_DQ<23>
  VSS121  = GND
  DQ26_B  = M_K_CPU1_SB_DQ<26>
  VSS122  = GND
  DQ27_B  = M_K_CPU1_SB_DQ<27>
  VSS123  = GND
  \dqs8_b_c||tdqs8_b_c\  = M_K_CPU1_SB_DQS_DN<8>
  \dqs8_b_t||tdqs8_b_t\  = M_K_CPU1_SB_DQS_DP<8>
  VSS124  = GND
  DQ30_B  = M_K_CPU1_SB_DQ<30>
  VSS125  = GND
  DQ31_B  = M_K_CPU1_SB_DQ<31>
  VSS126  = GND
  G1  = GND
  G2  = GND
  G3  = GND

(kicad_pcb
	(version 20260206)
	(generator "pcbnew")
	(generator_version "10.0")
	(general
		(thickness 1.6)
		(legacy_teardrops no)
	)
	(paper "A4")
	(title_block
		(title "04192023_DAF0TMB3IC0_F0TG_MB_C_brd_V02_OCP.brd")
		(comment 1 "Grand Teton / footprint 4555 of 8354 (J99), pads 47-92 of 291")
	)
	(layers
		(0 "F.Cu" signal "TOP")
		(4 "In1.Cu" signal "GND")
		(6 "In2.Cu" signal "IN1")
		(8 "In3.Cu" signal "GND1")
		(10 "In4.Cu" signal "IN2")
		(12 "In5.Cu" signal "GND2")
		(14 "In6.Cu" signal "IN3")
		(16 "In7.Cu" signal "GND3")
		(18 "In8.Cu" signal "VCC")
		(20 "In9.Cu" signal "VCC1")
		(22 "In10.Cu" signal "GND4")
		(24 "In11.Cu" signal "IN4")
		(26 "In12.Cu" signal "GND5")
		(28 "In13.Cu" signal "IN5")
		(30 "In14.Cu" signal "GND6")
		(32 "In15.Cu" signal "IN6")
		(34 "In16.Cu" signal "GND7")
		(2 "B.Cu" signal "BOTTOM")
		(9 "F.Adhes" user "F.Adhesive")
		(11 "B.Adhes" user "B.Adhesive")
		(13 "F.Paste" user "Package Geometry/Pastemask Top")
		(15 "B.Paste" user "Package Geometry/Pastemask Bottom")
		(5 "F.SilkS" user "Ref Des/Silkscreen Top")
		(7 "B.SilkS" user "Ref Des/Silkscreen Bottom")
		(1 "F.Mask" user "Board Geometry/Soldermask Top")
		(3 "B.Mask" user "Board Geometry/Soldermask Bottom")
		(17 "Dwgs.User" user "User.Drawings")
		(19 "Cmts.User" user "User.Comments")
		(21 "Eco1.User" user "User.Eco1")
		(23 "Eco2.User" user "User.Eco2")
		(25 "Edge.Cuts" user "Board Geometry/Outline")
		(27 "Margin" user)
		(31 "F.CrtYd" user "Package Geometry/Place Bound Top")
		(29 "B.CrtYd" user "Package Geometry/Place Bound Bottom")
		(35 "F.Fab" user "Ref Des/Assembly Top")
		(33 "B.Fab" user "Ref Des/Assembly Bottom")
	)
	(footprint ""
		(layer "F.Cu")
		(at 196.654166 -255.560322 180)
		(property "Reference" "J99"
			(at -0.4318 -81.730088 0)
			(unlocked yes)
			(layer "F.SilkS")
			(effects
				(font
					(size 0.7874 0.5842)
					(thickness 0.1524)
				)
			)
		)
		(property "Value" ""
			(at 0 0 180)
			(layer "F.Fab")
			(effects
				(font
					(size 1.27 1.27)
				)
			)
		)
		(duplicate_pad_numbers_are_jumpers no)
		(pad "47" smd rect
			(at -2.050034 -24.224996 90)
			(size 0.519938 1.4986)
			(layers "F.Cu" "F.Mask" "F.Paste")
			(net "M_K_CPU1_SA_DQ<28>")
		)
		(pad "48" smd rect
			(at -2.050034 -23.375112 90)
			(size 0.519938 1.4986)
			(layers "F.Cu" "F.Mask" "F.Paste")
			(net "GND")
		)
		(pad "49" smd rect
			(at -2.050034 -22.524974 90)
			(size 0.519938 1.4986)
			(layers "F.Cu" "F.Mask" "F.Paste")
			(net "M_K_CPU1_SA_DQ<29>")
		)
		(pad "50" smd rect
			(at -2.050034 -21.67509 90)
			(size 0.519938 1.4986)
			(layers "F.Cu" "F.Mask" "F.Paste")
			(net "GND")
		)
		(pad "51" smd rect
			(at -2.050034 -20.824952 90)
			(size 0.519938 1.4986)
			(layers "F.Cu" "F.Mask" "F.Paste")
			(net "M_K_CPU1_SA_CB<0>")
		)
		(pad "52" smd rect
			(at -2.050034 -19.975068 90)
			(size 0.519938 1.4986)
			(layers "F.Cu" "F.Mask" "F.Paste")
			(net "GND")
		)
		(pad "53" smd rect
			(at -2.050034 -19.12493 90)
			(size 0.519938 1.4986)
			(layers "F.Cu" "F.Mask" "F.Paste")
			(net "M_K_CPU1_SA_CB<1>")
		)
		(pad "54" smd rect
			(at -2.050034 -18.275046 90)
			(size 0.519938 1.4986)
			(layers "F.Cu" "F.Mask" "F.Paste")
			(net "GND")
		)
		(pad "55" smd rect
			(at -2.050034 -17.424908 90)
			(size 0.519938 1.4986)
			(layers "F.Cu" "F.Mask" "F.Paste")
			(net "M_K_CPU1_SA_DQS_DP<4>")
		)
		(pad "56" smd rect
			(at -2.050034 -16.575024 90)
			(size 0.519938 1.4986)
			(layers "F.Cu" "F.Mask" "F.Paste")
			(net "M_K_CPU1_SA_DQS_DN<4>")
		)
		(pad "57" smd rect
			(at -2.050034 -15.724886 90)
			(size 0.519938 1.4986)
			(layers "F.Cu" "F.Mask" "F.Paste")
			(net "GND")
		)
		(pad "58" smd rect
			(at -2.050034 -14.875002 90)
			(size 0.519938 1.4986)
			(layers "F.Cu" "F.Mask" "F.Paste")
			(net "M_K_CPU1_SA_CB<4>")
		)
		(pad "59" smd rect
			(at -2.050034 -14.025118 90)
			(size 0.519938 1.4986)
			(layers "F.Cu" "F.Mask" "F.Paste")
			(net "GND")
		)
		(pad "60" smd rect
			(at -2.050034 -13.17498 90)
			(size 0.519938 1.4986)
			(layers "F.Cu" "F.Mask" "F.Paste")
			(net "M_K_CPU1_SA_CB<5>")
		)
		(pad "61" smd rect
			(at -2.050034 -12.325096 90)
			(size 0.519938 1.4986)
			(layers "F.Cu" "F.Mask" "F.Paste")
			(net "GND")
		)
		(pad "62" smd rect
			(at -2.050034 -11.474958 90)
			(size 0.519938 1.4986)
			(layers "F.Cu" "F.Mask" "F.Paste")
			(net "M_K_CPU1_ALERT_N")
		)
		(pad "63" smd rect
			(at -2.050034 -10.625074 90)
			(size 0.519938 1.4986)
			(layers "F.Cu" "F.Mask" "F.Paste")
			(net "GND")
		)
		(pad "64" smd rect
			(at -2.050034 -9.774936 90)
			(size 0.519938 1.4986)
			(layers "F.Cu" "F.Mask" "F.Paste")
			(net "M_K_CPU1_SA_CS_N<0>")
		)
		(pad "65" smd rect
			(at -2.050034 -8.925052 90)
			(size 0.519938 1.4986)
			(layers "F.Cu" "F.Mask" "F.Paste")
			(net "GND")
		)
		(pad "66" smd rect
			(at -2.050034 -8.074914 90)
			(size 0.519938 1.4986)
			(layers "F.Cu" "F.Mask" "F.Paste")
			(net "M_K_CPU1_SA_CA<0>")
		)
		(pad "67" smd rect
			(at -2.050034 -7.22503 90)
			(size 0.519938 1.4986)
			(layers "F.Cu" "F.Mask" "F.Paste")
			(net "GND")
		)
		(pad "68" smd rect
			(at -2.050034 -6.374892 90)
			(size 0.519938 1.4986)
			(layers "F.Cu" "F.Mask" "F.Paste")
			(net "M_K_CPU1_SA_CA<2>")
		)
		(pad "69" smd rect
			(at -2.050034 -5.525008 90)
			(size 0.519938 1.4986)
			(layers "F.Cu" "F.Mask" "F.Paste")
			(net "GND")
		)
		(pad "70" smd rect
			(at -2.050034 -4.675124 90)
			(size 0.519938 1.4986)
			(layers "F.Cu" "F.Mask" "F.Paste")
			(net "M_K_CPU1_SA_CA<4>")
		)
		(pad "71" smd rect
			(at -2.050034 -3.824986 90)
			(size 0.519938 1.4986)
			(layers "F.Cu" "F.Mask" "F.Paste")
			(net "GND")
		)
		(pad "72" smd rect
			(at -2.050034 -2.975102 90)
			(size 0.519938 1.4986)
			(layers "F.Cu" "F.Mask" "F.Paste")
			(net "M_K_CPU1_SA_CA<6>")
		)
		(pad "73" smd rect
			(at -2.050034 -2.124964 90)
			(size 0.519938 1.4986)
			(layers "F.Cu" "F.Mask" "F.Paste")
			(net "GND")
		)
		(pad "74" smd rect
			(at -2.050034 -1.27508 90)
			(size 0.519938 1.4986)
			(layers "F.Cu" "F.Mask" "F.Paste")
			(net "M_K_CPU1_SA_PAR")
		)
		(pad "75" smd rect
			(at -2.050034 -0.424942 90)
			(size 0.519938 1.4986)
			(layers "F.Cu" "F.Mask" "F.Paste")
			(net "GND")
		)
		(pad "76" smd rect
			(at -2.050034 5.525008 90)
			(size 0.519938 1.4986)
			(layers "F.Cu" "F.Mask" "F.Paste")
			(net "M_K_CPU1_SB_CA<0>")
		)
		(pad "77" smd rect
			(at -2.050034 6.374892 90)
			(size 0.519938 1.4986)
			(layers "F.Cu" "F.Mask" "F.Paste")
			(net "GND")
		)
		(pad "78" smd rect
			(at -2.050034 7.22503 90)
			(size 0.519938 1.4986)
			(layers "F.Cu" "F.Mask" "F.Paste")
			(net "M_K_CPU1_SB_CA<2>")
		)
		(pad "79" smd rect
			(at -2.050034 8.074914 90)
			(size 0.519938 1.4986)
			(layers "F.Cu" "F.Mask" "F.Paste")
			(net "GND")
		)
		(pad "80" smd rect
			(at -2.050034 8.925052 90)
			(size 0.519938 1.4986)
			(layers "F.Cu" "F.Mask" "F.Paste")
			(net "M_K_CPU1_SB_CA<4>")
		)
		(pad "81" smd rect
			(at -2.050034 9.774936 90)
			(size 0.519938 1.4986)
			(layers "F.Cu" "F.Mask" "F.Paste")
			(net "GND")
		)
		(pad "82" smd rect
			(at -2.050034 10.625074 90)
			(size 0.519938 1.4986)
			(layers "F.Cu" "F.Mask" "F.Paste")
			(net "M_K_CPU1_SB_CA<6>")
		)
		(pad "83" smd rect
			(at -2.050034 11.474958 90)
			(size 0.519938 1.4986)
			(layers "F.Cu" "F.Mask" "F.Paste")
			(net "GND")
		)
		(pad "84" smd rect
			(at -2.050034 12.325096 90)
			(size 0.519938 1.4986)
			(layers "F.Cu" "F.Mask" "F.Paste")
			(net "M_K_CPU1_SB_CS_N<0>")
		)
		(pad "85" smd rect
			(at -2.050034 13.17498 90)
			(size 0.519938 1.4986)
			(layers "F.Cu" "F.Mask" "F.Paste")
			(net "GND")
		)
		(pad "86" smd rect
			(at -2.050034 14.025118 90)
			(size 0.519938 1.4986)
			(layers "F.Cu" "F.Mask" "F.Paste")
			(net "M_K_CPU1_SA_RSP<0>")
		)
		(pad "87" smd rect
			(at -2.050034 14.875002 90)
			(size 0.519938 1.4986)
			(layers "F.Cu" "F.Mask" "F.Paste")
			(net "M_K_CPU1_SB_RSP<0>")
		)
		(pad "88" smd rect
			(at -2.050034 15.724886 90)
			(size 0.519938 1.4986)
			(layers "F.Cu" "F.Mask" "F.Paste")
			(net "GND")
		)
		(pad "89" smd rect
			(at -2.050034 16.575024 90)
			(size 0.519938 1.4986)
			(layers "F.Cu" "F.Mask" "F.Paste")
			(net "M_K_CPU1_SB_CB<4>")
		)
		(pad "90" smd rect
			(at -2.050034 17.424908 90)
			(size 0.519938 1.4986)
			(layers "F.Cu" "F.Mask" "F.Paste")
			(net "GND")
		)
		(pad "91" smd rect
			(at -2.050034 18.275046 90)
			(size 0.519938 1.4986)
			(layers "F.Cu" "F.Mask" "F.Paste")
			(net "M_K_CPU1_SB_CB<5>")
		)
		(pad "92" smd rect
			(at -2.050034 19.12493 90)
			(size 0.519938 1.4986)
			(layers "F.Cu" "F.Mask" "F.Paste")
			(net "GND")
		)
	)
)
